# T6G (Grand Teton) — schematic netlist excerpt (pin names and nets, part order shuffled) for the footprints in the layout excerpt that follows; sources: Cadence DE-HDL packaged netlist, KiCad conversion of 04192023_DAF0TMB3IC0_F0TG_MB_C_brd_V02_OCP.brd

C6048  Q_CAP  0.1UF 25V 10% X7R  pkg 0402  page 177 : A = P3V3_AUX ; B = GND
C2659  Q_CAP  10UF 6.3V 20% X6S  pkg C0402  page 75 : A = PVDD_33_S5 ; B = GND

(kicad_pcb
	(version 20260206)
	(generator "pcbnew")
	(generator_version "10.0")
	(general
		(thickness 1.6)
		(legacy_teardrops no)
	)
	(paper "A4")
	(title_block
		(title "04192023_DAF0TMB3IC0_F0TG_MB_C_brd_V02_OCP.brd")
		(comment 1 "Grand Teton / footprints 5872-5873 of 8354")
	)
	(layers
		(0 "F.Cu" signal "TOP")
		(4 "In1.Cu" signal "GND")
		(6 "In2.Cu" signal "IN1")
		(8 "In3.Cu" signal "GND1")
		(10 "In4.Cu" signal "IN2")
		(12 "In5.Cu" signal "GND2")
		(14 "In6.Cu" signal "IN3")
		(16 "In7.Cu" signal "GND3")
		(18 "In8.Cu" signal "VCC")
		(20 "In9.Cu" signal "VCC1")
		(22 "In10.Cu" signal "GND4")
		(24 "In11.Cu" signal "IN4")
		(26 "In12.Cu" signal "GND5")
		(28 "In13.Cu" signal "IN5")
		(30 "In14.Cu" signal "GND6")
		(32 "In15.Cu" signal "IN6")
		(34 "In16.Cu" signal "GND7")
		(2 "B.Cu" signal "BOTTOM")
		(9 "F.Adhes" user "F.Adhesive")
		(11 "B.Adhes" user "B.Adhesive")
		(13 "F.Paste" user "Package Geometry/Pastemask Top")
		(15 "B.Paste" user "Package Geometry/Pastemask Bottom")
		(5 "F.SilkS" user "Ref Des/Silkscreen Top")
		(7 "B.SilkS" user "Ref Des/Silkscreen Bottom")
		(1 "F.Mask" user "Board Geometry/Soldermask Top")
		(3 "B.Mask" user "Board Geometry/Soldermask Bottom")
		(17 "Dwgs.User" user "User.Drawings")
		(19 "Cmts.User" user "User.Comments")
		(21 "Eco1.User" user "User.Eco1")
		(23 "Eco2.User" user "User.Eco2")
		(25 "Edge.Cuts" user "Board Geometry/Outline")
		(27 "Margin" user)
		(31 "F.CrtYd" user "Package Geometry/Place Bound Top")
		(29 "B.CrtYd" user "Package Geometry/Place Bound Bottom")
		(35 "F.Fab" user "Ref Des/Assembly Top")
		(33 "B.Fab" user "Ref Des/Assembly Bottom")
	)
	(footprint ""
		(layer "B.Cu")
		(at 98.454464 -266.640564)
		(property "Reference" "C2659"
			(at 0 0 0)
			(layer "B.SilkS")
			(hide yes)
			(effects
				(font
					(size 1.27 1.27)
				)
				(justify mirror)
			)
		)
		(property "Value" ""
			(at 0 0 0)
			(layer "B.Fab")
			(effects
				(font
					(size 1.27 1.27)
				)
				(justify mirror)
			)
		)
		(duplicate_pad_numbers_are_jumpers no)
		(fp_line
			(start -0.7874 -0.4064)
			(end -0.7874 0.4064)
			(stroke
				(width 0.1524)
				(type default)
			)
			(layer "B.SilkS")
		)
		(fp_line
			(start -0.7874 0.4064)
			(end 0.7874 0.4064)
			(stroke
				(width 0.1524)
				(type default)
			)
			(layer "B.SilkS")
		)
		(fp_line
			(start 0.7874 -0.4064)
			(end -0.7874 -0.4064)
			(stroke
				(width 0.1524)
				(type default)
			)
			(layer "B.SilkS")
		)
		(fp_line
			(start 0.7874 0.4064)
			(end 0.7874 -0.4064)
			(stroke
				(width 0.1524)
				(type default)
			)
			(layer "B.SilkS")
		)
		(fp_line
			(start -0.67945 -0.3048)
			(end -0.67945 0.3048)
			(stroke
				(width 0.1)
				(type default)
			)
			(layer "B.Fab")
		)
		(fp_line
			(start -0.67945 0.3048)
			(end -0.120396 0.3048)
			(stroke
				(width 0.1)
				(type default)
			)
			(layer "B.Fab")
		)
		(fp_line
			(start -0.12065 -0.3048)
			(end -0.67945 -0.3048)
			(stroke
				(width 0.1)
				(type default)
			)
			(layer "B.Fab")
		)
		(fp_line
			(start -0.12065 -0.2794)
			(end -0.12065 -0.3048)
			(stroke
				(width 0.1)
				(type default)
			)
			(layer "B.Fab")
		)
		(fp_line
			(start -0.120396 0.2794)
			(end 0.12065 0.2794)
			(stroke
				(width 0.1)
				(type default)
			)
			(layer "B.Fab")
		)
		(fp_line
			(start -0.120396 0.3048)
			(end -0.120396 0.2794)
			(stroke
				(width 0.1)
				(type default)
			)
			(layer "B.Fab")
		)
		(fp_line
			(start 0.12065 -0.305054)
			(end 0.12065 -0.2794)
			(stroke
				(width 0.1)
				(type default)
			)
			(layer "B.Fab")
		)
		(fp_line
			(start 0.12065 -0.2794)
			(end -0.12065 -0.2794)
			(stroke
				(width 0.1)
				(type default)
			)
			(layer "B.Fab")
		)
		(fp_line
			(start 0.12065 0.2794)
			(end 0.12065 0.3048)
			(stroke
				(width 0.1)
				(type default)
			)
			(layer "B.Fab")
		)
		(fp_line
			(start 0.12065 0.3048)
			(end 0.67945 0.3048)
			(stroke
				(width 0.1)
				(type default)
			)
			(layer "B.Fab")
		)
		(fp_line
			(start 0.67945 -0.305054)
			(end 0.12065 -0.305054)
			(stroke
				(width 0.1)
				(type default)
			)
			(layer "B.Fab")
		)
		(fp_line
			(start 0.67945 0.3048)
			(end 0.67945 -0.305054)
			(stroke
				(width 0.1)
				(type default)
			)
			(layer "B.Fab")
		)
		(pad "1" smd circle
			(at 0.40005 0 180)
			(size 0 0)
			(layers "B.Cu" "B.Mask" "B.Paste")
			(net "PVDD_33_S5")
		)
		(pad "2" smd circle
			(at -0.40005 0 180)
			(size 0 0)
			(layers "B.Cu" "B.Mask" "B.Paste")
			(net "GND")
		)
	)
	(footprint ""
		(layer "B.Cu")
		(at 134.262114 -33.834578 180)
		(property "Reference" "C6048"
			(at 0 0 0)
			(layer "B.SilkS")
			(hide yes)
			(effects
				(font
					(size 1.27 1.27)
				)
				(justify mirror)
			)
		)
		(property "Value" ""
			(at 0 0 0)
			(layer "B.Fab")
			(effects
				(font
					(size 1.27 1.27)
				)
				(justify mirror)
			)
		)
		(duplicate_pad_numbers_are_jumpers no)
		(fp_line
			(start 0.7874 0.4064)
			(end 0.7874 -0.4064)
			(stroke
				(width 0.1524)
				(type default)
			)
			(layer "B.SilkS")
		)
		(fp_line
			(start 0.7874 -0.4064)
			(end -0.7874 -0.4064)
			(stroke
				(width 0.1524)
				(type default)
			)
			(layer "B.SilkS")
		)
		(fp_line
			(start -0.7874 0.4064)
			(end 0.7874 0.4064)
			(stroke
				(width 0.1524)
				(type default)
			)
			(layer "B.SilkS")
		)
		(fp_line
			(start -0.7874 -0.4064)
			(end -0.7874 0.4064)
			(stroke
				(width 0.1524)
				(type default)
			)
			(layer "B.SilkS")
		)
		(fp_line
			(start 0.67945 0.3048)
			(end 0.67945 -0.305054)
			(stroke
				(width 0.1)
				(type default)
			)
			(layer "B.Fab")
		)
		(fp_line
			(start 0.67945 -0.305054)
			(end 0.12065 -0.305054)
			(stroke
				(width 0.1)
				(type default)
			)
			(layer "B.Fab")
		)
		(fp_line
			(start 0.12065 0.3048)
			(end 0.67945 0.3048)
			(stroke
				(width 0.1)
				(type default)
			)
			(layer "B.Fab")
		)
		(fp_line
			(start 0.12065 0.2794)
			(end 0.12065 0.3048)
			(stroke
				(width 0.1)
				(type default)
			)
			(layer "B.Fab")
		)
		(fp_line
			(start 0.12065 -0.2794)
			(end -0.12065 -0.2794)
			(stroke
				(width 0.1)
				(type default)
			)
			(layer "B.Fab")
		)
		(fp_line
			(start 0.12065 -0.305054)
			(end 0.12065 -0.2794)
			(stroke
				(width 0.1)
				(type default)
			)
			(layer "B.Fab")
		)
		(fp_line
			(start -0.120396 0.3048)
			(end -0.120396 0.2794)
			(stroke
				(width 0.1)
				(type default)
			)
			(layer "B.Fab")
		)
		(fp_line
			(start -0.120396 0.2794)
			(end 0.12065 0.2794)
			(stroke
				(width 0.1)
				(type default)
			)
			(layer "B.Fab")
		)
		(fp_line
			(start -0.12065 -0.2794)
			(end -0.12065 -0.3048)
			(stroke
				(width 0.1)
				(type default)
			)
			(layer "B.Fab")
		)
		(fp_line
			(start -0.12065 -0.3048)
			(end -0.67945 -0.3048)
			(stroke
				(width 0.1)
				(type default)
			)
			(layer "B.Fab")
		)
		(fp_line
			(start -0.67945 0.3048)
			(end -0.120396 0.3048)
			(stroke
				(width 0.1)
				(type default)
			)
			(layer "B.Fab")
		)
		(fp_line
			(start -0.67945 -0.3048)
			(end -0.67945 0.3048)
			(stroke
				(width 0.1)
				(type default)
			)
			(layer "B.Fab")
		)
		(pad "1" smd circle
			(at 0.40005 0)
			(size 0 0)
			(layers "B.Cu" "B.Mask" "B.Paste")
			(net "P3V3_AUX")
		)
		(pad "2" smd circle
			(at -0.40005 0)
			(size 0 0)
			(layers "B.Cu" "B.Mask" "B.Paste")
			(net "GND")
		)
	)
)
